# BASEBOARD_FAB2 (Tioga Pass) — schematic netlist excerpt (pin names and nets, part order shuffled) for the footprints in the layout excerpt that follows; sources: Cadence DE-HDL packaged netlist, KiCad conversion of Wiwynn_Tioga_Pass_MB.brd

EU1D4  IR354XX  IR35411 IC  pkg SM  page 207
  VOS  = PVCCIN_CPU1
  LGND  = GND
  VCC  = VR_PVCCIN_CPU1_PH2_VCIN
  VDRV  = P5V_STBY
  PGND(0)  = GND
  GL(0)  = TP_PVCCINC_CPU1_PH2_GL_0
  PGND(1)  = GND
  SW  = VR_PVCCIN_CPU1_PHASE2
  VIN(0)  = VR_FET_SW_P12V_STBY_PVCCIN_CPU1
  VIN(1)  = VR_FET_SW_P12V_STBY_PVCCIN_CPU1
  NC  = NC
  PHASE  = VR_PVCCIN_CPU1_PH2_PHASE
  BOOST  = VR_PVCCIN_CPU1_PH2_BOOT_R
  PWM  = VR_PVCCIN_CPU1_PWM2
  EN  = P5V_STBY
  TOUT_FLT  = A_TSENSE_PVCCIN_CPU1
  OCSET  = VR_PVCCIN_CPU1_PH2_OCSET
  IOUT  = ISENSE_PVCCIN_CPU1_PH2_IMON
  REFIN  = VR_PVCCIN_CPU1_AIREF2
  PGND(2)  = GND
  GL(1)  = TP_PVCCINC_CPU1_PH2_GL_1

(kicad_pcb
	(version 20260206)
	(generator "pcbnew")
	(generator_version "10.0")
	(general
		(thickness 1.6)
		(legacy_teardrops no)
	)
	(paper "A4")
	(title_block
		(title "Wiwynn_Tioga_Pass_MB.brd")
		(comment 1 "Tioga Pass / footprints 1018-1018 of 4770")
	)
	(layers
		(0 "F.Cu" signal "TOP")
		(4 "In1.Cu" signal "L2GND")
		(6 "In2.Cu" signal "L3")
		(8 "In3.Cu" signal "L4GND")
		(10 "In4.Cu" signal "L5")
		(12 "In5.Cu" signal "L6GND")
		(14 "In6.Cu" signal "L7VCC")
		(16 "In7.Cu" signal "L8VCC")
		(18 "In8.Cu" signal "L9GND")
		(20 "In9.Cu" signal "L10")
		(22 "In10.Cu" signal "L11GND")
		(24 "In11.Cu" signal "L12")
		(26 "In12.Cu" signal "L13GND")
		(2 "B.Cu" signal "BOTTOM")
		(9 "F.Adhes" user "F.Adhesive")
		(11 "B.Adhes" user "B.Adhesive")
		(13 "F.Paste" user "Package Geometry/Pastemask Top")
		(15 "B.Paste" user "Package Geometry/Pastemask Bottom")
		(5 "F.SilkS" user "Ref Des/Silkscreen Top")
		(7 "B.SilkS" user "Ref Des/Silkscreen Bottom")
		(1 "F.Mask" user "Board Geometry/Soldermask Top")
		(3 "B.Mask" user "Board Geometry/Soldermask Bottom")
		(17 "Dwgs.User" user "User.Drawings")
		(19 "Cmts.User" user "User.Comments")
		(21 "Eco1.User" user "User.Eco1")
		(23 "Eco2.User" user "User.Eco2")
		(25 "Edge.Cuts" user "Board Geometry/Outline")
		(27 "Margin" user)
		(31 "F.CrtYd" user "Package Geometry/Place Bound Top")
		(29 "B.CrtYd" user "Package Geometry/Place Bound Bottom")
		(35 "F.Fab" user "Ref Des/Assembly Top")
		(33 "B.Fab" user "Ref Des/Assembly Bottom")
	)
	(footprint ""
		(layer "F.Cu")
		(at 33.925002 -65.167764 90)
		(property "Reference" "EU1D4"
			(at 3.334766 -1.844802 0)
			(unlocked yes)
			(layer "F.SilkS")
			(effects
				(font
					(size 0.7874 0.5842)
					(thickness 0.1524)
				)
			)
		)
		(property "Value" ""
			(at 0 0 90)
			(layer "F.Fab")
			(effects
				(font
					(size 1.27 1.27)
				)
			)
		)
		(duplicate_pad_numbers_are_jumpers no)
		(fp_line
			(start 2.9718 -3.5052)
			(end 2.9718 3.429)
			(stroke
				(width 0.1524)
				(type default)
			)
			(layer "F.SilkS")
		)
		(fp_line
			(start -3.0099 -3.5052)
			(end 2.9718 -3.5052)
			(stroke
				(width 0.1524)
				(type default)
			)
			(layer "F.SilkS")
		)
		(fp_line
			(start 2.9718 3.429)
			(end -3.0099 3.429)
			(stroke
				(width 0.1524)
				(type default)
			)
			(layer "F.SilkS")
		)
		(fp_line
			(start -3.0099 3.429)
			(end -3.0099 -3.5052)
			(stroke
				(width 0.1524)
				(type default)
			)
			(layer "F.SilkS")
		)
		(fp_circle
			(center -3.057398 -2.678684)
			(end -3.057398 -2.551684)
			(stroke
				(width 0.254)
				(type default)
			)
			(fill no)
			(layer "F.SilkS")
		)
		(fp_poly
			(pts
				(xy -2.9972 -3.4925) (xy -2.9972 -2.6924) (xy -2.1971 -3.4925)
			)
			(stroke
				(width 0)
				(type default)
			)
			(fill yes)
			(layer "F.SilkS")
		)
		(fp_poly
			(pts
				(xy -2.549906 -3.050032) (xy -2.549906 3.050032) (xy 2.549906 3.050032) (xy 2.549906 -3.050032)
			)
			(stroke
				(width 0)
				(type default)
			)
			(fill no)
			(layer "F.CrtYd")
		)
		(fp_line
			(start 2.549906 -3.050032)
			(end 2.549906 3.050032)
			(stroke
				(width 0.1)
				(type default)
			)
			(layer "F.Fab")
		)
		(fp_line
			(start -2.549906 -3.050032)
			(end 2.549906 -3.050032)
			(stroke
				(width 0.1)
				(type default)
			)
			(layer "F.Fab")
		)
		(fp_line
			(start 2.549906 3.050032)
			(end -2.549906 3.050032)
			(stroke
				(width 0.1)
				(type default)
			)
			(layer "F.Fab")
		)
		(fp_line
			(start -2.549906 3.050032)
			(end -2.549906 -3.050032)
			(stroke
				(width 0.1)
				(type default)
			)
			(layer "F.Fab")
		)
		(fp_circle
			(center -3.057398 -2.678684)
			(end -3.057398 -2.551684)
			(stroke
				(width 0.254)
				(type default)
			)
			(fill no)
			(layer "F.Fab")
		)
		(pad "1" smd rect
			(at -2.39522 -2.279904 90)
			(size 0.7112 0.254)
			(layers "F.Cu" "F.Mask" "F.Paste")
			(net "PVCCIN_CPU1")
		)
		(pad "2" smd rect
			(at -2.39522 -1.83007 90)
			(size 0.7112 0.254)
			(layers "F.Cu" "F.Mask" "F.Paste")
			(net "GND")
		)
		(pad "3" smd rect
			(at -2.39522 -1.379982 90)
			(size 0.7112 0.254)
			(layers "F.Cu" "F.Mask" "F.Paste")
			(net "VR_PVCCIN_CPU1_PH2_VCIN")
		)
		(pad "4" smd rect
			(at -2.39522 -0.929894 90)
			(size 0.7112 0.254)
			(layers "F.Cu" "F.Mask" "F.Paste")
			(net "P5V_STBY")
		)
		(pad "5" smd rect
			(at -2.39522 -0.48006 90)
			(size 0.7112 0.254)
			(layers "F.Cu" "F.Mask" "F.Paste")
			(net "GND")
		)
		(pad "6" smd rect
			(at -2.39522 -0.029972 90)
			(size 0.7112 0.254)
			(layers "F.Cu" "F.Mask" "F.Paste")
			(net "TP_PVCCINC_CPU1_PH2_GL_0")
		)
		(pad "7" smd custom
			(at 0.016764 1.145032 90)
			(size 0.53975 0.53975)
			(layers "F.Cu" "F.Mask" "F.Paste")
			(net "GND")
			(options
				(clearance outline)
				(anchor circle)
			)
			(primitives
				(gr_poly
					(pts
						(xy -2.7051 1.0795) (xy -2.7051 -0.3683) (xy -0.9271 -0.3683) (xy -0.9271 -1.0795) (xy 2.7051 -1.0795)
						(xy 2.7051 1.0795)
					)
					(width 0)
					(fill yes)
				)
			)
		)
		(pad "10" smd rect
			(at -0.008382 2.874772 90)
			(size 4.3434 0.6096)
			(layers "F.Cu" "F.Mask" "F.Paste")
			(net "VR_PVCCIN_CPU1_PHASE2")
		)
		(pad "25" smd rect
			(at 1.548384 -1.283208 90)
			(size 2.3368 2.0066)
			(layers "F.Cu" "F.Mask" "F.Paste")
			(net "VR_FET_SW_P12V_STBY_PVCCIN_CPU1")
		)
		(pad "30" smd rect
			(at 2.050034 -2.895092 90)
			(size 0.254 0.7112)
			(layers "F.Cu" "F.Mask" "F.Paste")
			(net "VR_FET_SW_P12V_STBY_PVCCIN_CPU1")
		)
		(pad "31" smd rect
			(at 1.599946 -2.895092 90)
			(size 0.254 0.7112)
			(layers "F.Cu" "F.Mask" "F.Paste")
			(net "Net_357")
		)
		(pad "32" smd rect
			(at 1.150112 -2.895092 90)
			(size 0.254 0.7112)
			(layers "F.Cu" "F.Mask" "F.Paste")
			(net "VR_PVCCIN_CPU1_PH2_PHASE")
		)
		(pad "33" smd rect
			(at 0.700024 -2.895092 90)
			(size 0.254 0.7112)
			(layers "F.Cu" "F.Mask" "F.Paste")
			(net "VR_PVCCIN_CPU1_PH2_BOOT_R")
		)
		(pad "34" smd rect
			(at 0.249936 -2.895092 90)
			(size 0.254 0.7112)
			(layers "F.Cu" "F.Mask" "F.Paste")
			(net "VR_PVCCIN_CPU1_PWM2")
		)
		(pad "35" smd rect
			(at -0.199898 -2.895092 90)
			(size 0.254 0.7112)
			(layers "F.Cu" "F.Mask" "F.Paste")
			(net "P5V_STBY")
		)
		(pad "36" smd rect
			(at -0.649986 -2.895092 90)
			(size 0.254 0.7112)
			(layers "F.Cu" "F.Mask" "F.Paste")
			(net "A_TSENSE_PVCCIN_CPU1")
		)
		(pad "37" smd rect
			(at -1.100074 -2.895092 90)
			(size 0.254 0.7112)
			(layers "F.Cu" "F.Mask" "F.Paste")
			(net "VR_PVCCIN_CPU1_PH2_OCSET")
		)
		(pad "38" smd rect
			(at -1.549908 -2.895092 90)
			(size 0.254 0.7112)
			(layers "F.Cu" "F.Mask" "F.Paste")
			(net "ISENSE_PVCCIN_CPU1_PH2_IMON")
		)
		(pad "39" smd rect
			(at -1.999996 -2.895092 90)
			(size 0.254 0.7112)
			(layers "F.Cu" "F.Mask" "F.Paste")
			(net "VR_PVCCIN_CPU1_AIREF2")
		)
		(pad "40" smd rect
			(at -0.871728 -1.283208 90)
			(size 1.8034 2.0066)
			(layers "F.Cu" "F.Mask" "F.Paste")
			(net "GND")
		)
		(pad "41" smd rect
			(at -1.533906 0.247904 90)
			(size 0.508 0.3556)
			(layers "F.Cu" "F.Mask" "F.Paste")
			(net "TP_PVCCINC_CPU1_PH2_GL_1")
		)
	)
)
